(kicad_pcb
	(version 20260206)
	(generator "pcbnew")
	(generator_version "10.0")
	(general
		(thickness 1.6)
		(legacy_teardrops no)
	)
	(paper "A4")
	(title_block
		(title "01162023_DA0F0TEBIF0_F0T_Expander_BD_F_brd_V02_OCP.brd")
		(comment 1 "Grand Teton / footprint 6619 of 9728 (PEX0), pads 955-1072 of 2397")
	)
	(layers
		(0 "F.Cu" signal "TOP")
		(4 "In1.Cu" signal "GND")
		(6 "In2.Cu" signal "VCC")
		(8 "In3.Cu" signal "VCC1")
		(10 "In4.Cu" signal "GND1")
		(12 "In5.Cu" signal "IN1")
		(14 "In6.Cu" signal "GND2")
		(16 "In7.Cu" signal "IN2")
		(18 "In8.Cu" signal "GND3")
		(20 "In9.Cu" signal "IN3")
		(22 "In10.Cu" signal "GND4")
		(24 "In11.Cu" signal "IN4")
		(26 "In12.Cu" signal "GND5")
		(28 "In13.Cu" signal "IN5")
		(30 "In14.Cu" signal "GND6")
		(32 "In15.Cu" signal "IN6")
		(34 "In16.Cu" signal "GND7")
		(2 "B.Cu" signal "BOTTOM")
		(9 "F.Adhes" user "F.Adhesive")
		(11 "B.Adhes" user "B.Adhesive")
		(13 "F.Paste" user "Package Geometry/Pastemask Top")
		(15 "B.Paste" user "Package Geometry/Pastemask Bottom")
		(5 "F.SilkS" user "Ref Des/Silkscreen Top")
		(7 "B.SilkS" user "Ref Des/Silkscreen Bottom")
		(1 "F.Mask" user "Board Geometry/Soldermask Top")
		(3 "B.Mask" user "Board Geometry/Soldermask Bottom")
		(17 "Dwgs.User" user "User.Drawings")
		(19 "Cmts.User" user "User.Comments")
		(21 "Eco1.User" user "User.Eco1")
		(23 "Eco2.User" user "User.Eco2")
		(25 "Edge.Cuts" user "Board Geometry/Outline")
		(27 "Margin" user)
		(31 "F.CrtYd" user "Package Geometry/Place Bound Top")
		(29 "B.CrtYd" user "Package Geometry/Place Bound Bottom")
		(35 "F.Fab" user "Ref Des/Assembly Top")
		(33 "B.Fab" user "Ref Des/Assembly Bottom")
	)
	(footprint ""
		(layer "F.Cu")
		(at 59.649868 -295.89984)
		(property "Reference" "PEX0"
			(at -3.360166 35.566858 0)
			(unlocked yes)
			(layer "F.SilkS")
			(effects
				(font
					(size 2.032 1.524)
					(thickness 0.1524)
				)
				(justify left)
			)
		)
		(property "Value" ""
			(at 0 0 0)
			(layer "F.Fab")
			(effects
				(font
					(size 1.27 1.27)
				)
			)
		)
		(duplicate_pad_numbers_are_jumpers no)
		(pad "AW26" smd circle
			(at 0.94996 13.299948)
			(size 0.4572 0.4572)
			(layers "F.Cu" "F.Mask" "F.Paste")
			(net "PEX0_DBG_MODE3")
		)
		(pad "AW27" smd circle
			(at 1.89992 13.299948)
			(size 0.4572 0.4572)
			(layers "F.Cu" "F.Mask" "F.Paste")
			(net "PEX0_MODE_SEL0")
		)
		(pad "AW28" smd circle
			(at 2.84988 13.299948)
			(size 0.4572 0.4572)
			(layers "F.Cu" "F.Mask" "F.Paste")
			(net "PEX0_MODE_SEL4")
		)
		(pad "AW29" smd circle
			(at 3.800094 13.299948)
			(size 0.4572 0.4572)
			(layers "F.Cu" "F.Mask" "F.Paste")
			(net "PEX0_MODE_SEL8")
		)
		(pad "AW30" smd circle
			(at 4.750054 13.299948)
			(size 0.4572 0.4572)
			(layers "F.Cu" "F.Mask" "F.Paste")
			(net "PEX0_DBG_MODE2")
		)
		(pad "AW31" smd circle
			(at 5.700014 13.299948)
			(size 0.4572 0.4572)
			(layers "F.Cu" "F.Mask" "F.Paste")
			(net "PEX0_MODE_SEL11")
		)
		(pad "AW32" smd circle
			(at 6.649974 13.299948)
			(size 0.4572 0.4572)
			(layers "F.Cu" "F.Mask" "F.Paste")
			(net "PEX0_MODE_SEL12")
		)
		(pad "AW33" smd circle
			(at 7.599934 13.299948)
			(size 0.4572 0.4572)
			(layers "F.Cu" "F.Mask" "F.Paste")
			(net "Net_2868")
		)
		(pad "AW34" smd circle
			(at 8.549894 13.299948)
			(size 0.4572 0.4572)
			(layers "F.Cu" "F.Mask" "F.Paste")
			(net "PEX0_DBG_MODE4")
		)
		(pad "AW35" smd circle
			(at 9.500108 13.299948)
			(size 0.4572 0.4572)
			(layers "F.Cu" "F.Mask" "F.Paste")
			(net "Net_2847")
		)
		(pad "AW36" smd circle
			(at 10.450068 13.299948)
			(size 0.4572 0.4572)
			(layers "F.Cu" "F.Mask" "F.Paste")
			(net "Net_2871")
		)
		(pad "AW37" smd circle
			(at 11.400028 13.299948)
			(size 0.4572 0.4572)
			(layers "F.Cu" "F.Mask" "F.Paste")
			(net "Net_2875")
		)
		(pad "AW38" smd circle
			(at 12.349988 13.299948)
			(size 0.4572 0.4572)
			(layers "F.Cu" "F.Mask" "F.Paste")
			(net "PEX0_MODE_SEL1")
		)
		(pad "AW39" smd circle
			(at 13.299948 13.299948)
			(size 0.4572 0.4572)
			(layers "F.Cu" "F.Mask" "F.Paste")
			(net "Net_2842")
		)
		(pad "AW40" smd circle
			(at 14.249908 13.299948)
			(size 0.4572 0.4572)
			(layers "F.Cu" "F.Mask" "F.Paste")
			(net "GND")
		)
		(pad "AW41" smd circle
			(at 15.200122 13.299948)
			(size 0.4572 0.4572)
			(layers "F.Cu" "F.Mask" "F.Paste")
			(net "GND")
		)
		(pad "AW42" smd circle
			(at 16.150082 13.299948)
			(size 0.4572 0.4572)
			(layers "F.Cu" "F.Mask" "F.Paste")
			(net "GND")
		)
		(pad "AW43" smd circle
			(at 17.100042 13.299948)
			(size 0.4572 0.4572)
			(layers "F.Cu" "F.Mask" "F.Paste")
			(net "P5E_PEX0_STN0_TX_DP<6>")
		)
		(pad "AW44" smd circle
			(at 18.050002 13.299948)
			(size 0.4572 0.4572)
			(layers "F.Cu" "F.Mask" "F.Paste")
			(net "P5E_PEX0_STN0_TX_DN<6>")
		)
		(pad "AW45" smd circle
			(at 18.999962 13.299948)
			(size 0.4572 0.4572)
			(layers "F.Cu" "F.Mask" "F.Paste")
			(net "GND")
		)
		(pad "AW46" smd circle
			(at 19.949922 13.299948)
			(size 0.4572 0.4572)
			(layers "F.Cu" "F.Mask" "F.Paste")
			(net "P5E_PEX0_STN0_RX_DP<6>")
		)
		(pad "AW47" smd circle
			(at 20.899882 13.299948)
			(size 0.4572 0.4572)
			(layers "F.Cu" "F.Mask" "F.Paste")
			(net "P5E_PEX0_STN0_RX_DN<6>")
		)
		(pad "AW48" smd circle
			(at 21.850096 13.299948)
			(size 0.4572 0.4572)
			(layers "F.Cu" "F.Mask" "F.Paste")
			(net "GND")
		)
		(pad "AW49" smd circle
			(at 22.800056 13.299948)
			(size 0.4572 0.4572)
			(layers "F.Cu" "F.Mask" "F.Paste")
			(net "GND")
		)
		(pad "AY1" smd circle
			(at -22.800056 14.249908)
			(size 0.4572 0.4572)
			(layers "F.Cu" "F.Mask" "F.Paste")
			(net "Net_2716")
		)
		(pad "AY2" smd circle
			(at -21.850096 14.249908)
			(size 0.4572 0.4572)
			(layers "F.Cu" "F.Mask" "F.Paste")
			(net "Net_2730")
		)
		(pad "AY3" smd circle
			(at -20.899882 14.249908)
			(size 0.4572 0.4572)
			(layers "F.Cu" "F.Mask" "F.Paste")
			(net "GND")
		)
		(pad "AY4" smd circle
			(at -19.949922 14.249908)
			(size 0.4572 0.4572)
			(layers "F.Cu" "F.Mask" "F.Paste")
			(net "GND")
		)
		(pad "AY5" smd circle
			(at -18.999962 14.249908)
			(size 0.4572 0.4572)
			(layers "F.Cu" "F.Mask" "F.Paste")
			(net "GND")
		)
		(pad "AY6" smd circle
			(at -18.050002 14.249908)
			(size 0.4572 0.4572)
			(layers "F.Cu" "F.Mask" "F.Paste")
			(net "GND")
		)
		(pad "AY7" smd circle
			(at -17.100042 14.249908)
			(size 0.4572 0.4572)
			(layers "F.Cu" "F.Mask" "F.Paste")
			(net "GND")
		)
		(pad "AY8" smd circle
			(at -16.150082 14.249908)
			(size 0.4572 0.4572)
			(layers "F.Cu" "F.Mask" "F.Paste")
			(net "GND")
		)
		(pad "AY9" smd circle
			(at -15.200122 14.249908)
			(size 0.4572 0.4572)
			(layers "F.Cu" "F.Mask" "F.Paste")
			(net "GND")
		)
		(pad "AY10" smd circle
			(at -14.249908 14.249908)
			(size 0.4572 0.4572)
			(layers "F.Cu" "F.Mask" "F.Paste")
			(net "GND")
		)
		(pad "AY11" smd circle
			(at -13.299948 14.249908)
			(size 0.4572 0.4572)
			(layers "F.Cu" "F.Mask" "F.Paste")
			(net "GND")
		)
		(pad "AY12" smd circle
			(at -12.349988 14.249908)
			(size 0.4572 0.4572)
			(layers "F.Cu" "F.Mask" "F.Paste")
			(net "GND")
		)
		(pad "AY13" smd circle
			(at -11.400028 14.249908)
			(size 0.4572 0.4572)
			(layers "F.Cu" "F.Mask" "F.Paste")
			(net "GND")
		)
		(pad "AY14" smd circle
			(at -10.450068 14.249908)
			(size 0.4572 0.4572)
			(layers "F.Cu" "F.Mask" "F.Paste")
			(net "GND")
		)
		(pad "AY15" smd circle
			(at -9.500108 14.249908)
			(size 0.4572 0.4572)
			(layers "F.Cu" "F.Mask" "F.Paste")
			(net "GND")
		)
		(pad "AY16" smd circle
			(at -8.549894 14.249908)
			(size 0.4572 0.4572)
			(layers "F.Cu" "F.Mask" "F.Paste")
			(net "GND")
		)
		(pad "AY17" smd circle
			(at -7.599934 14.249908)
			(size 0.4572 0.4572)
			(layers "F.Cu" "F.Mask" "F.Paste")
			(net "GND")
		)
		(pad "AY18" smd circle
			(at -6.649974 14.249908)
			(size 0.4572 0.4572)
			(layers "F.Cu" "F.Mask" "F.Paste")
			(net "GND")
		)
		(pad "AY19" smd circle
			(at -5.700014 14.249908)
			(size 0.4572 0.4572)
			(layers "F.Cu" "F.Mask" "F.Paste")
			(net "GND")
		)
		(pad "AY20" smd circle
			(at -4.750054 14.249908)
			(size 0.4572 0.4572)
			(layers "F.Cu" "F.Mask" "F.Paste")
			(net "GND")
		)
		(pad "AY21" smd circle
			(at -3.800094 14.249908)
			(size 0.4572 0.4572)
			(layers "F.Cu" "F.Mask" "F.Paste")
			(net "GND")
		)
		(pad "AY22" smd circle
			(at -2.84988 14.249908)
			(size 0.4572 0.4572)
			(layers "F.Cu" "F.Mask" "F.Paste")
			(net "GND")
		)
		(pad "AY23" smd circle
			(at -1.89992 14.249908)
			(size 0.4572 0.4572)
			(layers "F.Cu" "F.Mask" "F.Paste")
			(net "GND")
		)
		(pad "AY24" smd circle
			(at -0.94996 14.249908)
			(size 0.4572 0.4572)
			(layers "F.Cu" "F.Mask" "F.Paste")
			(net "GND")
		)
		(pad "AY25" smd circle
			(at 0 14.249908)
			(size 0.4572 0.4572)
			(layers "F.Cu" "F.Mask" "F.Paste")
			(net "GND")
		)
		(pad "AY26" smd circle
			(at 0.94996 14.249908)
			(size 0.4572 0.4572)
			(layers "F.Cu" "F.Mask" "F.Paste")
			(net "GND")
		)
		(pad "AY27" smd circle
			(at 1.89992 14.249908)
			(size 0.4572 0.4572)
			(layers "F.Cu" "F.Mask" "F.Paste")
			(net "GND")
		)
		(pad "AY28" smd circle
			(at 2.84988 14.249908)
			(size 0.4572 0.4572)
			(layers "F.Cu" "F.Mask" "F.Paste")
			(net "GND")
		)
		(pad "AY29" smd circle
			(at 3.800094 14.249908)
			(size 0.4572 0.4572)
			(layers "F.Cu" "F.Mask" "F.Paste")
			(net "GND")
		)
		(pad "AY30" smd circle
			(at 4.750054 14.249908)
			(size 0.4572 0.4572)
			(layers "F.Cu" "F.Mask" "F.Paste")
			(net "GND")
		)
		(pad "AY31" smd circle
			(at 5.700014 14.249908)
			(size 0.4572 0.4572)
			(layers "F.Cu" "F.Mask" "F.Paste")
			(net "GND")
		)
		(pad "AY32" smd circle
			(at 6.649974 14.249908)
			(size 0.4572 0.4572)
			(layers "F.Cu" "F.Mask" "F.Paste")
			(net "GND")
		)
		(pad "AY33" smd circle
			(at 7.599934 14.249908)
			(size 0.4572 0.4572)
			(layers "F.Cu" "F.Mask" "F.Paste")
			(net "GND")
		)
		(pad "AY34" smd circle
			(at 8.549894 14.249908)
			(size 0.4572 0.4572)
			(layers "F.Cu" "F.Mask" "F.Paste")
			(net "GND")
		)
		(pad "AY35" smd circle
			(at 9.500108 14.249908)
			(size 0.4572 0.4572)
			(layers "F.Cu" "F.Mask" "F.Paste")
			(net "GND")
		)
		(pad "AY36" smd circle
			(at 10.450068 14.249908)
			(size 0.4572 0.4572)
			(layers "F.Cu" "F.Mask" "F.Paste")
			(net "GND")
		)
		(pad "AY37" smd circle
			(at 11.400028 14.249908)
			(size 0.4572 0.4572)
			(layers "F.Cu" "F.Mask" "F.Paste")
			(net "GND")
		)
		(pad "AY38" smd circle
			(at 12.349988 14.249908)
			(size 0.4572 0.4572)
			(layers "F.Cu" "F.Mask" "F.Paste")
			(net "GND")
		)
		(pad "AY39" smd circle
			(at 13.299948 14.249908)
			(size 0.4572 0.4572)
			(layers "F.Cu" "F.Mask" "F.Paste")
			(net "GND")
		)
		(pad "AY40" smd circle
			(at 14.249908 14.249908)
			(size 0.4572 0.4572)
			(layers "F.Cu" "F.Mask" "F.Paste")
			(net "GND")
		)
		(pad "AY41" smd circle
			(at 15.200122 14.249908)
			(size 0.4572 0.4572)
			(layers "F.Cu" "F.Mask" "F.Paste")
			(net "GND")
		)
		(pad "AY42" smd circle
			(at 16.150082 14.249908)
			(size 0.4572 0.4572)
			(layers "F.Cu" "F.Mask" "F.Paste")
			(net "GND")
		)
		(pad "AY43" smd circle
			(at 17.100042 14.249908)
			(size 0.4572 0.4572)
			(layers "F.Cu" "F.Mask" "F.Paste")
			(net "GND")
		)
		(pad "AY44" smd circle
			(at 18.050002 14.249908)
			(size 0.4572 0.4572)
			(layers "F.Cu" "F.Mask" "F.Paste")
			(net "GND")
		)
		(pad "AY45" smd circle
			(at 18.999962 14.249908)
			(size 0.4572 0.4572)
			(layers "F.Cu" "F.Mask" "F.Paste")
			(net "GND")
		)
		(pad "AY46" smd circle
			(at 19.949922 14.249908)
			(size 0.4572 0.4572)
			(layers "F.Cu" "F.Mask" "F.Paste")
			(net "GND")
		)
		(pad "AY47" smd circle
			(at 20.899882 14.249908)
			(size 0.4572 0.4572)
			(layers "F.Cu" "F.Mask" "F.Paste")
			(net "GND")
		)
		(pad "AY48" smd circle
			(at 21.850096 14.249908)
			(size 0.4572 0.4572)
			(layers "F.Cu" "F.Mask" "F.Paste")
			(net "P5E_PEX0_STN0_RX_DP<7>")
		)
		(pad "AY49" smd circle
			(at 22.800056 14.249908)
			(size 0.4572 0.4572)
			(layers "F.Cu" "F.Mask" "F.Paste")
			(net "P5E_PEX0_STN0_RX_DN<7>")
		)
		(pad "B1" smd circle
			(at -22.800056 -21.850096)
			(size 0.4572 0.4572)
			(layers "F.Cu" "F.Mask" "F.Paste")
			(net "GND")
		)
		(pad "B2" smd circle
			(at -21.850096 -21.850096)
			(size 0.4572 0.4572)
			(layers "F.Cu" "F.Mask" "F.Paste")
			(net "GND")
		)
		(pad "B3" smd circle
			(at -20.899882 -21.850096)
			(size 0.4572 0.4572)
			(layers "F.Cu" "F.Mask" "F.Paste")
			(net "P5E_PEX0_STN7_RX_DP<123>")
		)
		(pad "B4" smd circle
			(at -19.949922 -21.850096)
			(size 0.4572 0.4572)
			(layers "F.Cu" "F.Mask" "F.Paste")
			(net "GND")
		)
		(pad "B5" smd circle
			(at -18.999962 -21.850096)
			(size 0.4572 0.4572)
			(layers "F.Cu" "F.Mask" "F.Paste")
			(net "P5E_PEX0_STN7_RX_DP<125>")
		)
		(pad "B6" smd circle
			(at -18.050002 -21.850096)
			(size 0.4572 0.4572)
			(layers "F.Cu" "F.Mask" "F.Paste")
			(net "GND")
		)
		(pad "B7" smd circle
			(at -17.100042 -21.850096)
			(size 0.4572 0.4572)
			(layers "F.Cu" "F.Mask" "F.Paste")
			(net "P5E_PEX0_STN7_RX_DP<127>")
		)
		(pad "B8" smd circle
			(at -16.150082 -21.850096)
			(size 0.4572 0.4572)
			(layers "F.Cu" "F.Mask" "F.Paste")
			(net "GND")
		)
		(pad "B9" smd circle
			(at -15.200122 -21.850096)
			(size 0.4572 0.4572)
			(layers "F.Cu" "F.Mask" "F.Paste")
			(net "P5E_PEX0_STN6_RX_DP<110>")
		)
		(pad "B10" smd circle
			(at -14.249908 -21.850096)
			(size 0.4572 0.4572)
			(layers "F.Cu" "F.Mask" "F.Paste")
			(net "GND")
		)
		(pad "B11" smd circle
			(at -13.299948 -21.850096)
			(size 0.4572 0.4572)
			(layers "F.Cu" "F.Mask" "F.Paste")
			(net "P5E_PEX0_STN6_RX_DP<108>")
		)
		(pad "B12" smd circle
			(at -12.349988 -21.850096)
			(size 0.4572 0.4572)
			(layers "F.Cu" "F.Mask" "F.Paste")
			(net "GND")
		)
		(pad "B13" smd circle
			(at -11.400028 -21.850096)
			(size 0.4572 0.4572)
			(layers "F.Cu" "F.Mask" "F.Paste")
			(net "P5E_PEX0_STN6_RX_DP<106>")
		)
		(pad "B14" smd circle
			(at -10.450068 -21.850096)
			(size 0.4572 0.4572)
			(layers "F.Cu" "F.Mask" "F.Paste")
			(net "GND")
		)
		(pad "B15" smd circle
			(at -9.500108 -21.850096)
			(size 0.4572 0.4572)
			(layers "F.Cu" "F.Mask" "F.Paste")
			(net "P5E_PEX0_STN6_RX_DP<104>")
		)
		(pad "B16" smd circle
			(at -8.549894 -21.850096)
			(size 0.4572 0.4572)
			(layers "F.Cu" "F.Mask" "F.Paste")
			(net "GND")
		)
		(pad "B17" smd circle
			(at -7.599934 -21.850096)
			(size 0.4572 0.4572)
			(layers "F.Cu" "F.Mask" "F.Paste")
			(net "P5E_PEX0_STN6_RX_DP<102>")
		)
		(pad "B18" smd circle
			(at -6.649974 -21.850096)
			(size 0.4572 0.4572)
			(layers "F.Cu" "F.Mask" "F.Paste")
			(net "GND")
		)
		(pad "B19" smd circle
			(at -5.700014 -21.850096)
			(size 0.4572 0.4572)
			(layers "F.Cu" "F.Mask" "F.Paste")
			(net "P5E_PEX0_STN6_RX_DP<100>")
		)
		(pad "B20" smd circle
			(at -4.750054 -21.850096)
			(size 0.4572 0.4572)
			(layers "F.Cu" "F.Mask" "F.Paste")
			(net "GND")
		)
		(pad "B21" smd circle
			(at -3.800094 -21.850096)
			(size 0.4572 0.4572)
			(layers "F.Cu" "F.Mask" "F.Paste")
			(net "P5E_PEX0_STN6_RX_DP<98>")
		)
		(pad "B22" smd circle
			(at -2.84988 -21.850096)
			(size 0.4572 0.4572)
			(layers "F.Cu" "F.Mask" "F.Paste")
			(net "GND")
		)
		(pad "B23" smd circle
			(at -1.89992 -21.850096)
			(size 0.4572 0.4572)
			(layers "F.Cu" "F.Mask" "F.Paste")
			(net "P5E_PEX0_STN6_RX_DP<96>")
		)
		(pad "B24" smd circle
			(at -0.94996 -21.850096)
			(size 0.4572 0.4572)
			(layers "F.Cu" "F.Mask" "F.Paste")
			(net "GND")
		)
		(pad "B25" smd circle
			(at 0 -21.850096)
			(size 0.4572 0.4572)
			(layers "F.Cu" "F.Mask" "F.Paste")
			(net "P5E_PEX0_STN5_RX_DP<81>")
		)
		(pad "B26" smd circle
			(at 0.94996 -21.850096)
			(size 0.4572 0.4572)
			(layers "F.Cu" "F.Mask" "F.Paste")
			(net "GND")
		)
		(pad "B27" smd circle
			(at 1.89992 -21.850096)
			(size 0.4572 0.4572)
			(layers "F.Cu" "F.Mask" "F.Paste")
			(net "P5E_PEX0_STN5_RX_DP<83>")
		)
		(pad "B28" smd circle
			(at 2.84988 -21.850096)
			(size 0.4572 0.4572)
			(layers "F.Cu" "F.Mask" "F.Paste")
			(net "GND")
		)
		(pad "B29" smd circle
			(at 3.800094 -21.850096)
			(size 0.4572 0.4572)
			(layers "F.Cu" "F.Mask" "F.Paste")
			(net "P5E_PEX0_STN5_RX_DP<85>")
		)
		(pad "B30" smd circle
			(at 4.750054 -21.850096)
			(size 0.4572 0.4572)
			(layers "F.Cu" "F.Mask" "F.Paste")
			(net "GND")
		)
		(pad "B31" smd circle
			(at 5.700014 -21.850096)
			(size 0.4572 0.4572)
			(layers "F.Cu" "F.Mask" "F.Paste")
			(net "P5E_PEX0_STN5_RX_DP<87>")
		)
		(pad "B32" smd circle
			(at 6.649974 -21.850096)
			(size 0.4572 0.4572)
			(layers "F.Cu" "F.Mask" "F.Paste")
			(net "GND")
		)
		(pad "B33" smd circle
			(at 7.599934 -21.850096)
			(size 0.4572 0.4572)
			(layers "F.Cu" "F.Mask" "F.Paste")
			(net "P5E_PEX0_STN5_RX_DP<89>")
		)
		(pad "B34" smd circle
			(at 8.549894 -21.850096)
			(size 0.4572 0.4572)
			(layers "F.Cu" "F.Mask" "F.Paste")
			(net "GND")
		)
		(pad "B35" smd circle
			(at 9.500108 -21.850096)
			(size 0.4572 0.4572)
			(layers "F.Cu" "F.Mask" "F.Paste")
			(net "P5E_PEX0_STN5_RX_DP<91>")
		)
		(pad "B36" smd circle
			(at 10.450068 -21.850096)
			(size 0.4572 0.4572)
			(layers "F.Cu" "F.Mask" "F.Paste")
			(net "GND")
		)
		(pad "B37" smd circle
			(at 11.400028 -21.850096)
			(size 0.4572 0.4572)
			(layers "F.Cu" "F.Mask" "F.Paste")
			(net "P5E_PEX0_STN5_RX_DP<93>")
		)
		(pad "B38" smd circle
			(at 12.349988 -21.850096)
			(size 0.4572 0.4572)
			(layers "F.Cu" "F.Mask" "F.Paste")
			(net "GND")
		)
		(pad "B39" smd circle
			(at 13.299948 -21.850096)
			(size 0.4572 0.4572)
			(layers "F.Cu" "F.Mask" "F.Paste")
			(net "P5E_PEX0_STN5_RX_DP<95>")
		)
		(pad "B40" smd circle
			(at 14.249908 -21.850096)
			(size 0.4572 0.4572)
			(layers "F.Cu" "F.Mask" "F.Paste")
			(net "GND")
		)
		(pad "B41" smd circle
			(at 15.200122 -21.850096)
			(size 0.4572 0.4572)
			(layers "F.Cu" "F.Mask" "F.Paste")
			(net "P5E_PEX0_STN4_RX_DP<78>")
		)
		(pad "B42" smd circle
			(at 16.150082 -21.850096)
			(size 0.4572 0.4572)
			(layers "F.Cu" "F.Mask" "F.Paste")
			(net "GND")
		)
		(pad "B43" smd circle
			(at 17.100042 -21.850096)
			(size 0.4572 0.4572)
			(layers "F.Cu" "F.Mask" "F.Paste")
			(net "P5E_PEX0_STN4_RX_DP<76>")
		)
		(pad "B44" smd circle
			(at 18.050002 -21.850096)
			(size 0.4572 0.4572)
			(layers "F.Cu" "F.Mask" "F.Paste")
			(net "GND")
		)
		(pad "B45" smd circle
			(at 18.999962 -21.850096)
			(size 0.4572 0.4572)
			(layers "F.Cu" "F.Mask" "F.Paste")
			(net "P5E_PEX0_STN4_RX_DP<74>")
		)
	)
)
